FILE_TYPE = MULTI_PHYS_TABLE;
PART 'TTL3126'
{========================================================================================}
:VALUE        | PACK_TYPE | MATERIAL | PART_NUMBER     = EnvComp                  | PART_NUMBER  | JEDEC_TYPE        | CLASS | DESCRIPTION                               | HEIGHT     | COMPONENT_TYPE | LEAD_LENGTH| LPID   | SPEED_URL                                                                                                                       | Status |RPL| AML | Bus_Unit | Days ;
{========================================================================================}
'74CBTLV3126' | 'QFNLF'   | 'IC'     | 'D18317-001'(!) = 'YES;YES;YES;UNK;ok;VLD' | 'D18317-001' | 'QFN14_14_14_5MA' | 'IC'  | 'LOW VOLTAGE QUAD BUS SWITCH'             | '0.039 IN' | 'LCC'          | ''         | '1642' | 'http://speed.intel.com:8081/speed/module/pdm/item/pdm_item_detail_direct.asp?item_cde=D18317-001&item_rev=01&url_param=unused' | 'Preliminary' | 'YES' | '1' | 'SMO_IC' | '84' 
'74CBTLV3126' | 'QFNLF'   | 'EMPTY'  | 'D18317-001'(!) = 'YES;YES;YES;UNK;ok;VLD' | 'D18317-001' | 'QFN14_14_14_5MA' | 'IO'  | 'LOW VOLTAGE QUAD BUS SWITCH'             | '0.039 IN' | 'LCC'          | ''         | '1642' | 'http://speed.intel.com:8081/speed/module/pdm/item/pdm_item_detail_direct.asp?item_cde=D18317-001&item_rev=01&url_param=unused' | 'Preliminary' | 'YES' | '1' | 'SMO_IC' | '84' 
END_PART
END.
